(kicad_pcb
	(version 20260206)
	(generator "pcbnew")
	(generator_version "10.0")
	(general
		(thickness 1.6)
		(legacy_teardrops no)
	)
	(paper "A4")
	(title_block
		(title "04192023_DAF0TMB3IC0_F0TG_MB_C_brd_V02_OCP.brd")
		(comment 1 "Grand Teton / footprints 639-646 of 8354")
	)
	(layers
		(0 "F.Cu" signal "TOP")
		(4 "In1.Cu" signal "GND")
		(6 "In2.Cu" signal "IN1")
		(8 "In3.Cu" signal "GND1")
		(10 "In4.Cu" signal "IN2")
		(12 "In5.Cu" signal "GND2")
		(14 "In6.Cu" signal "IN3")
		(16 "In7.Cu" signal "GND3")
		(18 "In8.Cu" signal "VCC")
		(20 "In9.Cu" signal "VCC1")
		(22 "In10.Cu" signal "GND4")
		(24 "In11.Cu" signal "IN4")
		(26 "In12.Cu" signal "GND5")
		(28 "In13.Cu" signal "IN5")
		(30 "In14.Cu" signal "GND6")
		(32 "In15.Cu" signal "IN6")
		(34 "In16.Cu" signal "GND7")
		(2 "B.Cu" signal "BOTTOM")
		(9 "F.Adhes" user "F.Adhesive")
		(11 "B.Adhes" user "B.Adhesive")
		(13 "F.Paste" user "Package Geometry/Pastemask Top")
		(15 "B.Paste" user "Package Geometry/Pastemask Bottom")
		(5 "F.SilkS" user "Ref Des/Silkscreen Top")
		(7 "B.SilkS" user "Ref Des/Silkscreen Bottom")
		(1 "F.Mask" user "Board Geometry/Soldermask Top")
		(3 "B.Mask" user "Board Geometry/Soldermask Bottom")
		(17 "Dwgs.User" user "User.Drawings")
		(19 "Cmts.User" user "User.Comments")
		(21 "Eco1.User" user "User.Eco1")
		(23 "Eco2.User" user "User.Eco2")
		(25 "Edge.Cuts" user "Board Geometry/Outline")
		(27 "Margin" user)
		(31 "F.CrtYd" user "Package Geometry/Place Bound Top")
		(29 "B.CrtYd" user "Package Geometry/Place Bound Bottom")
		(35 "F.Fab" user "Ref Des/Assembly Top")
		(33 "B.Fab" user "Ref Des/Assembly Bottom")
	)
	(footprint ""
		(layer "F.Cu")
		(at 484.834946 -306.882292 -90)
		(property "Reference" "X9010"
			(at -1.79451 4.909312 0)
			(unlocked yes)
			(layer "F.SilkS")
			(effects
				(font
					(size 0.7874 0.5842)
					(thickness 0.1524)
				)
				(justify left)
			)
		)
		(property "Value" ""
			(at 0 0 270)
			(layer "F.Fab")
			(effects
				(font
					(size 1.27 1.27)
				)
			)
		)
		(property "User Part Number" "N_A"
			(at 1.30175 1.27 0)
			(unlocked yes)
			(layer "Cmts.User")
			(hide yes)
			(effects
				(font
					(size 0.635 0.4064)
					(thickness 0.1524)
				)
			)
		)
		(property "Device Type" "TP_TDR_4P_FTS_TH-TP_TDR_4P_DIP,EMPTY,TP15"
			(at 1.30175 1.27 0)
			(unlocked yes)
			(layer "F.Fab")
			(hide yes)
			(effects
				(font
					(size 0.635 0.4064)
					(thickness 0.1524)
				)
			)
		)
		(duplicate_pad_numbers_are_jumpers no)
		(fp_line
			(start 0 3.81)
			(end 2.54 3.81)
			(stroke
				(width 0.1524)
				(type default)
			)
			(layer "F.SilkS")
		)
		(fp_line
			(start 2.54 3.81)
			(end 2.54 3.6703)
			(stroke
				(width 0.1524)
				(type default)
			)
			(layer "F.SilkS")
		)
		(fp_line
			(start 0 3.175)
			(end 0 3.81)
			(stroke
				(width 0.1524)
				(type default)
			)
			(layer "F.SilkS")
		)
		(fp_line
			(start 2.54 1.4097)
			(end 2.54 1.1303)
			(stroke
				(width 0.1524)
				(type default)
			)
			(layer "F.SilkS")
		)
		(fp_line
			(start 0 0.635)
			(end 0 1.905)
			(stroke
				(width 0.1524)
				(type default)
			)
			(layer "F.SilkS")
		)
		(fp_line
			(start 2.54 -1.1303)
			(end 2.54 -1.27)
			(stroke
				(width 0.1524)
				(type default)
			)
			(layer "F.SilkS")
		)
		(fp_line
			(start 0 -1.27)
			(end 0 -0.635)
			(stroke
				(width 0.1524)
				(type default)
			)
			(layer "F.SilkS")
		)
		(fp_line
			(start 2.54 -1.27)
			(end 0 -1.27)
			(stroke
				(width 0.1524)
				(type default)
			)
			(layer "F.SilkS")
		)
		(fp_poly
			(pts
				(xy -2.285746 -0.762) (xy -0.761746 0) (xy -2.285746 0.762)
			)
			(stroke
				(width 0)
				(type default)
			)
			(fill yes)
			(layer "F.SilkS")
		)
		(fp_line
			(start 0 3.81)
			(end 2.54 3.81)
			(stroke
				(width 0.1)
				(type default)
			)
			(layer "F.Fab")
		)
		(fp_line
			(start 2.54 3.81)
			(end 2.54 -1.27)
			(stroke
				(width 0.1)
				(type default)
			)
			(layer "F.Fab")
		)
		(fp_line
			(start 0 -1.27)
			(end 0 3.81)
			(stroke
				(width 0.1)
				(type default)
			)
			(layer "F.Fab")
		)
		(fp_line
			(start 2.54 -1.27)
			(end 0 -1.27)
			(stroke
				(width 0.1)
				(type default)
			)
			(layer "F.Fab")
		)
		(fp_poly
			(pts
				(xy -0.761746 0) (xy -2.285746 -0.762) (xy -2.285746 0.762)
			)
			(stroke
				(width 0)
				(type default)
			)
			(fill yes)
			(layer "F.Fab")
		)
		(pad "1" thru_hole circle
			(at 0 0 270)
			(size 1.0033 1.0033)
			(drill 0.249936)
			(layers "*.Cu" "*.Mask")
			(remove_unused_layers no)
			(net "TDR_DIFF_85_NECK_IN3_DN")
			(clearance 0.10795)
			(thermal_gap 0.10795)
			(padstack
				(mode front_inner_back)
				(layer "Inner"
					(shape circle)
					(size 0.8001 0.8001)
					(clearance 0.1524)
				)
				(layer "B.Cu"
					(shape circle)
					(size 1.0033 1.0033)
					(clearance 0.10795)
				)
			)
		)
		(pad "2" thru_hole circle
			(at 2.54 0 270)
			(size 1.9939 1.9939)
			(drill 0.249936)
			(layers "*.Cu" "*.Mask")
			(remove_unused_layers no)
			(net "T1_GND")
			(clearance 0.10795)
			(thermal_gap 0.10795)
			(padstack
				(mode front_inner_back)
				(layer "Inner"
					(shape circle)
					(size 0.8001 0.8001)
					(clearance 0.1524)
				)
				(layer "B.Cu"
					(shape circle)
					(size 1.9939 1.9939)
					(clearance 0.10795)
				)
			)
		)
		(pad "3" thru_hole circle
			(at 2.54 2.54 270)
			(size 1.9939 1.9939)
			(drill 0.249936)
			(layers "*.Cu" "*.Mask")
			(remove_unused_layers no)
			(net "T1_GND")
			(clearance 0.10795)
			(thermal_gap 0.10795)
			(padstack
				(mode front_inner_back)
				(layer "Inner"
					(shape circle)
					(size 0.8001 0.8001)
					(clearance 0.1524)
				)
				(layer "B.Cu"
					(shape circle)
					(size 1.9939 1.9939)
					(clearance 0.10795)
				)
			)
		)
		(pad "4" thru_hole circle
			(at 0 2.54 270)
			(size 1.0033 1.0033)
			(drill 0.249936)
			(layers "*.Cu" "*.Mask")
			(remove_unused_layers no)
			(net "TDR_DIFF_85_NECK_IN3_DP")
			(clearance 0.10795)
			(thermal_gap 0.10795)
			(padstack
				(mode front_inner_back)
				(layer "Inner"
					(shape circle)
					(size 0.8001 0.8001)
					(clearance 0.1524)
				)
				(layer "B.Cu"
					(shape circle)
					(size 1.0033 1.0033)
					(clearance 0.10795)
				)
			)
		)
	)
	(footprint ""
		(layer "F.Cu")
		(at 428.322232 -430.892458 180)
		(property "Reference" "C6086"
			(at 0 0 180)
			(layer "F.SilkS")
			(hide yes)
			(effects
				(font
					(size 1.27 1.27)
				)
			)
		)
		(property "Value" ""
			(at 0 0 180)
			(layer "F.Fab")
			(effects
				(font
					(size 1.27 1.27)
				)
			)
		)
		(duplicate_pad_numbers_are_jumpers no)
		(fp_line
			(start 0.7874 0.4064)
			(end -0.7874 0.4064)
			(stroke
				(width 0.1524)
				(type default)
			)
			(layer "F.SilkS")
		)
		(fp_line
			(start 0.7874 -0.4064)
			(end 0.7874 0.4064)
			(stroke
				(width 0.1524)
				(type default)
			)
			(layer "F.SilkS")
		)
		(fp_line
			(start -0.7874 0.4064)
			(end -0.7874 -0.4064)
			(stroke
				(width 0.1524)
				(type default)
			)
			(layer "F.SilkS")
		)
		(fp_line
			(start -0.7874 -0.4064)
			(end 0.7874 -0.4064)
			(stroke
				(width 0.1524)
				(type default)
			)
			(layer "F.SilkS")
		)
		(fp_line
			(start 0.67945 0.3048)
			(end 0.120396 0.3048)
			(stroke
				(width 0.1)
				(type default)
			)
			(layer "F.Fab")
		)
		(fp_line
			(start 0.67945 -0.3048)
			(end 0.67945 0.3048)
			(stroke
				(width 0.1)
				(type default)
			)
			(layer "F.Fab")
		)
		(fp_line
			(start 0.12065 -0.2794)
			(end 0.12065 -0.3048)
			(stroke
				(width 0.1)
				(type default)
			)
			(layer "F.Fab")
		)
		(fp_line
			(start 0.12065 -0.3048)
			(end 0.67945 -0.3048)
			(stroke
				(width 0.1)
				(type default)
			)
			(layer "F.Fab")
		)
		(fp_line
			(start 0.120396 0.3048)
			(end 0.120396 0.2794)
			(stroke
				(width 0.1)
				(type default)
			)
			(layer "F.Fab")
		)
		(fp_line
			(start 0.120396 0.2794)
			(end -0.12065 0.2794)
			(stroke
				(width 0.1)
				(type default)
			)
			(layer "F.Fab")
		)
		(fp_line
			(start -0.12065 0.3048)
			(end -0.67945 0.3048)
			(stroke
				(width 0.1)
				(type default)
			)
			(layer "F.Fab")
		)
		(fp_line
			(start -0.12065 0.2794)
			(end -0.12065 0.3048)
			(stroke
				(width 0.1)
				(type default)
			)
			(layer "F.Fab")
		)
		(fp_line
			(start -0.12065 -0.2794)
			(end 0.12065 -0.2794)
			(stroke
				(width 0.1)
				(type default)
			)
			(layer "F.Fab")
		)
		(fp_line
			(start -0.12065 -0.305054)
			(end -0.12065 -0.2794)
			(stroke
				(width 0.1)
				(type default)
			)
			(layer "F.Fab")
		)
		(fp_line
			(start -0.67945 0.3048)
			(end -0.67945 -0.305054)
			(stroke
				(width 0.1)
				(type default)
			)
			(layer "F.Fab")
		)
		(fp_line
			(start -0.67945 -0.305054)
			(end -0.12065 -0.305054)
			(stroke
				(width 0.1)
				(type default)
			)
			(layer "F.Fab")
		)
		(pad "1" smd circle
			(at -0.40005 0 180)
			(size 0 0)
			(layers "F.Cu" "F.Mask" "F.Paste")
			(net "HSC_TYPE_ADC")
		)
		(pad "2" smd circle
			(at 0.40005 0 180)
			(size 0 0)
			(layers "F.Cu" "F.Mask" "F.Paste")
			(net "GND")
		)
	)
	(footprint ""
		(layer "F.Cu")
		(at 239.94999 -39.420038)
		(property "Reference" "H76"
			(at -0.155702 -3.208274 0)
			(unlocked yes)
			(layer "B.SilkS")
			(effects
				(font
					(size 0.7874 0.5842)
					(thickness 0.1524)
				)
				(justify left mirror)
			)
		)
		(property "Value" ""
			(at 0 0 0)
			(layer "F.Fab")
			(effects
				(font
					(size 1.27 1.27)
				)
			)
		)
		(duplicate_pad_numbers_are_jumpers no)
		(pad "1" thru_hole rect
			(at 0 0)
			(size 4.2164 5.0038)
			(drill 2.0066
				(offset 0.099822 0)
			)
			(layers "*.Cu" "*.Mask")
			(remove_unused_layers no)
			(net "GND")
			(clearance -0.8509)
			(padstack
				(mode front_inner_back)
				(layer "Inner"
					(shape circle)
					(size 4.0132 4.0132)
					(clearance -0.7493)
				)
				(layer "B.Cu"
					(shape circle)
					(size 4.0132 4.0132)
					(clearance -0.7493)
				)
			)
		)
	)
	(footprint ""
		(layer "F.Cu")
		(at 404.564342 -416.899344 -90)
		(property "Reference" "C6588"
			(at 0 0 270)
			(layer "F.SilkS")
			(hide yes)
			(effects
				(font
					(size 1.27 1.27)
				)
			)
		)
		(property "Value" ""
			(at 0 0 270)
			(layer "F.Fab")
			(effects
				(font
					(size 1.27 1.27)
				)
			)
		)
		(duplicate_pad_numbers_are_jumpers no)
		(fp_line
			(start -0.299974 0.150114)
			(end -0.299974 -0.150114)
			(stroke
				(width 0.1)
				(type default)
			)
			(layer "F.Fab")
		)
		(fp_line
			(start 0.299974 0.150114)
			(end -0.299974 0.150114)
			(stroke
				(width 0.1)
				(type default)
			)
			(layer "F.Fab")
		)
		(fp_line
			(start -0.299974 -0.150114)
			(end 0.299974 -0.150114)
			(stroke
				(width 0.1)
				(type default)
			)
			(layer "F.Fab")
		)
		(fp_line
			(start 0.299974 -0.150114)
			(end 0.299974 0.150114)
			(stroke
				(width 0.1)
				(type default)
			)
			(layer "F.Fab")
		)
		(pad "1" smd rect
			(at -0.2667 0 270)
			(size 0.3048 0.381)
			(layers "F.Cu" "F.Mask" "F.Paste")
			(net "P5E_CPU0_P2_TX_BUF_C_DN<11>")
		)
		(pad "2" smd rect
			(at 0.2667 0 270)
			(size 0.3048 0.381)
			(layers "F.Cu" "F.Mask" "F.Paste")
			(net "P5E_CPU0_P2_TX_BUF_DN<11>")
		)
	)
	(footprint ""
		(layer "F.Cu")
		(at 369.687094 -404.873206 -90)
		(property "Reference" "R1108"
			(at 0 0 270)
			(layer "F.SilkS")
			(hide yes)
			(effects
				(font
					(size 1.27 1.27)
				)
			)
		)
		(property "Value" ""
			(at 0 0 270)
			(layer "F.Fab")
			(effects
				(font
					(size 1.27 1.27)
				)
			)
		)
		(duplicate_pad_numbers_are_jumpers no)
		(fp_line
			(start -0.32512 0.175006)
			(end -0.32512 -0.175006)
			(stroke
				(width 0.1)
				(type default)
			)
			(layer "F.Fab")
		)
		(fp_line
			(start 0.32512 0.175006)
			(end -0.32512 0.175006)
			(stroke
				(width 0.1)
				(type default)
			)
			(layer "F.Fab")
		)
		(fp_line
			(start -0.32512 -0.175006)
			(end 0.32512 -0.175006)
			(stroke
				(width 0.1)
				(type default)
			)
			(layer "F.Fab")
		)
		(fp_line
			(start 0.32512 -0.175006)
			(end 0.32512 0.175006)
			(stroke
				(width 0.1)
				(type default)
			)
			(layer "F.Fab")
		)
		(pad "1" smd rect
			(at -0.2667 0 270)
			(size 0.3048 0.381)
			(layers "F.Cu" "F.Mask" "F.Paste")
			(net "P1V8_CPU0_RT_1D")
		)
		(pad "2" smd rect
			(at 0.2667 0 90)
			(size 0.3048 0.381)
			(layers "F.Cu" "F.Mask" "F.Paste")
			(net "JTAG_TEST_MODE_RT_CPU0_P3")
		)
	)
	(footprint ""
		(layer "F.Cu")
		(at 193.167 -129.377948 90)
		(property "Reference" "R1564"
			(at 0 0 90)
			(layer "F.SilkS")
			(hide yes)
			(effects
				(font
					(size 1.27 1.27)
				)
			)
		)
		(property "Value" ""
			(at 0 0 90)
			(layer "F.Fab")
			(effects
				(font
					(size 1.27 1.27)
				)
			)
		)
		(duplicate_pad_numbers_are_jumpers no)
		(fp_line
			(start 0.7874 -0.4064)
			(end 0.7874 0.4064)
			(stroke
				(width 0.1524)
				(type default)
			)
			(layer "F.SilkS")
		)
		(fp_line
			(start -0.7874 -0.4064)
			(end 0.7874 -0.4064)
			(stroke
				(width 0.1524)
				(type default)
			)
			(layer "F.SilkS")
		)
		(fp_line
			(start 0.7874 0.4064)
			(end -0.7874 0.4064)
			(stroke
				(width 0.1524)
				(type default)
			)
			(layer "F.SilkS")
		)
		(fp_line
			(start -0.7874 0.4064)
			(end -0.7874 -0.4064)
			(stroke
				(width 0.1524)
				(type default)
			)
			(layer "F.SilkS")
		)
		(fp_line
			(start -0.12065 -0.305054)
			(end -0.12065 -0.2794)
			(stroke
				(width 0.1)
				(type default)
			)
			(layer "F.Fab")
		)
		(fp_line
			(start -0.67945 -0.305054)
			(end -0.12065 -0.305054)
			(stroke
				(width 0.1)
				(type default)
			)
			(layer "F.Fab")
		)
		(fp_line
			(start 0.67945 -0.3048)
			(end 0.67945 0.3048)
			(stroke
				(width 0.1)
				(type default)
			)
			(layer "F.Fab")
		)
		(fp_line
			(start 0.12065 -0.3048)
			(end 0.67945 -0.3048)
			(stroke
				(width 0.1)
				(type default)
			)
			(layer "F.Fab")
		)
		(fp_line
			(start 0.12065 -0.2794)
			(end 0.12065 -0.3048)
			(stroke
				(width 0.1)
				(type default)
			)
			(layer "F.Fab")
		)
		(fp_line
			(start -0.12065 -0.2794)
			(end 0.12065 -0.2794)
			(stroke
				(width 0.1)
				(type default)
			)
			(layer "F.Fab")
		)
		(fp_line
			(start 0.120396 0.2794)
			(end -0.12065 0.2794)
			(stroke
				(width 0.1)
				(type default)
			)
			(layer "F.Fab")
		)
		(fp_line
			(start -0.12065 0.2794)
			(end -0.12065 0.3048)
			(stroke
				(width 0.1)
				(type default)
			)
			(layer "F.Fab")
		)
		(fp_line
			(start 0.67945 0.3048)
			(end 0.120396 0.3048)
			(stroke
				(width 0.1)
				(type default)
			)
			(layer "F.Fab")
		)
		(fp_line
			(start 0.120396 0.3048)
			(end 0.120396 0.2794)
			(stroke
				(width 0.1)
				(type default)
			)
			(layer "F.Fab")
		)
		(fp_line
			(start -0.12065 0.3048)
			(end -0.67945 0.3048)
			(stroke
				(width 0.1)
				(type default)
			)
			(layer "F.Fab")
		)
		(fp_line
			(start -0.67945 0.3048)
			(end -0.67945 -0.305054)
			(stroke
				(width 0.1)
				(type default)
			)
			(layer "F.Fab")
		)
		(pad "1" smd circle
			(at -0.40005 0 90)
			(size 0 0)
			(layers "F.Cu" "F.Mask" "F.Paste")
			(net "FM_ROM_LS_EN")
		)
		(pad "2" smd circle
			(at 0.40005 0 90)
			(size 0 0)
			(layers "F.Cu" "F.Mask" "F.Paste")
			(net "ROM_LS_EN")
		)
	)
	(footprint ""
		(layer "F.Cu")
		(at 67.71513 -339.857588 90)
		(property "Reference" "PC404_3"
			(at 0 0 90)
			(layer "F.SilkS")
			(hide yes)
			(effects
				(font
					(size 1.27 1.27)
				)
			)
		)
		(property "Value" ""
			(at 0 0 90)
			(layer "F.Fab")
			(effects
				(font
					(size 1.27 1.27)
				)
			)
		)
		(duplicate_pad_numbers_are_jumpers no)
		(fp_line
			(start 0.7874 -0.4064)
			(end 0.7874 0.4064)
			(stroke
				(width 0.1524)
				(type default)
			)
			(layer "F.SilkS")
		)
		(fp_line
			(start -0.7874 -0.4064)
			(end 0.7874 -0.4064)
			(stroke
				(width 0.1524)
				(type default)
			)
			(layer "F.SilkS")
		)
		(fp_line
			(start 0.7874 0.4064)
			(end -0.7874 0.4064)
			(stroke
				(width 0.1524)
				(type default)
			)
			(layer "F.SilkS")
		)
		(fp_line
			(start -0.7874 0.4064)
			(end -0.7874 -0.4064)
			(stroke
				(width 0.1524)
				(type default)
			)
			(layer "F.SilkS")
		)
		(fp_line
			(start -0.12065 -0.305054)
			(end -0.12065 -0.2794)
			(stroke
				(width 0.1)
				(type default)
			)
			(layer "F.Fab")
		)
		(fp_line
			(start -0.67945 -0.305054)
			(end -0.12065 -0.305054)
			(stroke
				(width 0.1)
				(type default)
			)
			(layer "F.Fab")
		)
		(fp_line
			(start 0.67945 -0.3048)
			(end 0.67945 0.3048)
			(stroke
				(width 0.1)
				(type default)
			)
			(layer "F.Fab")
		)
		(fp_line
			(start 0.12065 -0.3048)
			(end 0.67945 -0.3048)
			(stroke
				(width 0.1)
				(type default)
			)
			(layer "F.Fab")
		)
		(fp_line
			(start 0.12065 -0.2794)
			(end 0.12065 -0.3048)
			(stroke
				(width 0.1)
				(type default)
			)
			(layer "F.Fab")
		)
		(fp_line
			(start -0.12065 -0.2794)
			(end 0.12065 -0.2794)
			(stroke
				(width 0.1)
				(type default)
			)
			(layer "F.Fab")
		)
		(fp_line
			(start 0.120396 0.2794)
			(end -0.12065 0.2794)
			(stroke
				(width 0.1)
				(type default)
			)
			(layer "F.Fab")
		)
		(fp_line
			(start -0.12065 0.2794)
			(end -0.12065 0.3048)
			(stroke
				(width 0.1)
				(type default)
			)
			(layer "F.Fab")
		)
		(fp_line
			(start 0.67945 0.3048)
			(end 0.120396 0.3048)
			(stroke
				(width 0.1)
				(type default)
			)
			(layer "F.Fab")
		)
		(fp_line
			(start 0.120396 0.3048)
			(end 0.120396 0.2794)
			(stroke
				(width 0.1)
				(type default)
			)
			(layer "F.Fab")
		)
		(fp_line
			(start -0.12065 0.3048)
			(end -0.67945 0.3048)
			(stroke
				(width 0.1)
				(type default)
			)
			(layer "F.Fab")
		)
		(fp_line
			(start -0.67945 0.3048)
			(end -0.67945 -0.305054)
			(stroke
				(width 0.1)
				(type default)
			)
			(layer "F.Fab")
		)
		(pad "1" smd circle
			(at -0.40005 0 90)
			(size 0 0)
			(layers "F.Cu" "F.Mask" "F.Paste")
			(net "PVDDCR_CPU1_P1_VCCS")
		)
		(pad "2" smd circle
			(at 0.40005 0 90)
			(size 0 0)
			(layers "F.Cu" "F.Mask" "F.Paste")
			(net "GND")
		)
	)
	(footprint ""
		(layer "F.Cu")
		(at 410.53004 -383.88163 -90)
		(property "Reference" "C855"
			(at 0 0 270)
			(layer "F.SilkS")
			(hide yes)
			(effects
				(font
					(size 1.27 1.27)
				)
			)
		)
		(property "Value" ""
			(at 0 0 270)
			(layer "F.Fab")
			(effects
				(font
					(size 1.27 1.27)
				)
			)
		)
		(duplicate_pad_numbers_are_jumpers no)
		(fp_line
			(start -0.299974 0.150114)
			(end -0.299974 -0.150114)
			(stroke
				(width 0.1)
				(type default)
			)
			(layer "F.Fab")
		)
		(fp_line
			(start 0.299974 0.150114)
			(end -0.299974 0.150114)
			(stroke
				(width 0.1)
				(type default)
			)
			(layer "F.Fab")
		)
		(fp_line
			(start -0.299974 -0.150114)
			(end 0.299974 -0.150114)
			(stroke
				(width 0.1)
				(type default)
			)
			(layer "F.Fab")
		)
		(fp_line
			(start 0.299974 -0.150114)
			(end 0.299974 0.150114)
			(stroke
				(width 0.1)
				(type default)
			)
			(layer "F.Fab")
		)
		(pad "1" smd rect
			(at -0.2667 0 270)
			(size 0.3048 0.381)
			(layers "F.Cu" "F.Mask" "F.Paste")
			(net "P5E_CPU0_P2_TX_C_DP<7>")
		)
		(pad "2" smd rect
			(at 0.2667 0 270)
			(size 0.3048 0.381)
			(layers "F.Cu" "F.Mask" "F.Paste")
			(net "P5E_CPU0_P2_TX_DP<7>")
		)
	)
)
